(kicad_pcb
	(version 20240108)
	(generator "pcbnew")
	(generator_version "8.0")
	(general
		(thickness 1.6)
		(legacy_teardrops no)
	)
	(paper "A4")
	(title_block
		(title "Jetson Orin Baseboard OCuLink Expansion")
		(date "2025-03-18")
		(rev "1.1.0")
		(company "Antmicro Ltd")
		(comment 1 "www.antmicro.com")
		(comment 9 "footprints 63-67 of 119")
	)
	(layers
		(0 "F.Cu" signal)
		(1 "In1.Cu" signal)
		(2 "In2.Cu" signal)
		(31 "B.Cu" signal)
		(32 "B.Adhes" user "B.Adhesive")
		(33 "F.Adhes" user "F.Adhesive")
		(34 "B.Paste" user)
		(35 "F.Paste" user)
		(36 "B.SilkS" user "B.Silkscreen")
		(37 "F.SilkS" user "F.Silkscreen")
		(38 "B.Mask" user)
		(39 "F.Mask" user)
		(40 "Dwgs.User" user "User.Drawings")
		(41 "Cmts.User" user "User.Comments")
		(42 "Eco1.User" user "User.Eco1")
		(43 "Eco2.User" user "User.Eco2")
		(44 "Edge.Cuts" user)
		(45 "Margin" user)
		(46 "B.CrtYd" user "B.Courtyard")
		(47 "F.CrtYd" user "F.Courtyard")
		(48 "B.Fab" user)
		(49 "F.Fab" user)
	)
	(footprint "antmicro-footprints:oshw-logo"
		(layer "B.Cu")
		(at 143.945 95.042 180)
		(descr "OSHW Logo")
		(tags "OSHW Logo")
		(property "Reference" "N1"
			(at 0 4.4 0)
			(layer "B.SilkS")
			(hide yes)
			(effects
				(font
					(size 0.7 0.7)
					(thickness 0.15)
				)
				(justify left bottom mirror)
			)
		)
		(property "Value" "oshw_logo"
			(at 0 3.4 0)
			(layer "B.Fab")
			(hide yes)
			(effects
				(font
					(size 0.7 0.7)
					(thickness 0.15)
				)
				(justify left bottom mirror)
			)
		)
		(property "Footprint" "antmicro-footprints:oshw-logo"
			(at 0 0 0)
			(layer "B.Fab")
			(hide yes)
			(effects
				(font
					(size 1.27 1.27)
					(thickness 0.15)
				)
				(justify mirror)
			)
		)
		(property "Description" "Mechanical part"
			(at 0 0 0)
			(layer "B.Fab")
			(hide yes)
			(effects
				(font
					(size 1.27 1.27)
					(thickness 0.15)
				)
				(justify mirror)
			)
		)
		(property "Author" "Antmicro"
			(at 0 0 0)
			(unlocked yes)
			(layer "B.Fab")
			(hide yes)
			(effects
				(font
					(size 1 1)
					(thickness 0.15)
				)
				(justify mirror)
			)
		)
		(property "License" "Apache-2.0"
			(at 0 0 0)
			(unlocked yes)
			(layer "B.Fab")
			(hide yes)
			(effects
				(font
					(size 1 1)
					(thickness 0.15)
				)
				(justify mirror)
			)
		)
		(property "MPN" ""
			(at 0 0 0)
			(unlocked yes)
			(layer "B.Fab")
			(hide yes)
			(effects
				(font
					(size 1 1)
					(thickness 0.15)
				)
				(justify mirror)
			)
		)
		(property "Manufacturer" ""
			(at 0 0 0)
			(unlocked yes)
			(layer "B.Fab")
			(hide yes)
			(effects
				(font
					(size 1 1)
					(thickness 0.15)
				)
				(justify mirror)
			)
		)
		(sheetname "Root")
		(sheetfile "jetson-orin-baseboard-oculink-expansion.kicad_sch")
		(attr exclude_from_pos_files exclude_from_bom allow_soldermask_bridges)
	)
	(footprint "antmicro-footprints:R_0402_1005Metric"
		(layer "B.Cu")
		(at 118.325 113.973751 180)
		(descr "Resistor SMD 0402")
		(tags "resistor SMD 0402")
		(property "Reference" "R4"
			(at -2.588333 -0.47725 0)
			(layer "B.SilkS")
			(effects
				(font
					(size 0.7 0.7)
					(thickness 0.15)
				)
				(justify left bottom mirror)
			)
		)
		(property "Value" "R_1k_0402"
			(at -1.011843 -1.772047 0)
			(layer "B.Fab")
			(effects
				(font
					(size 0.7 0.7)
					(thickness 0.15)
				)
				(justify left bottom mirror)
			)
		)
		(property "Footprint" "antmicro-footprints:R_0402_1005Metric"
			(at 0 0 0)
			(layer "B.Fab")
			(hide yes)
			(effects
				(font
					(size 1.27 1.27)
					(thickness 0.15)
				)
				(justify mirror)
			)
		)
		(property "Datasheet" "https://www.bourns.com/docs/product-datasheets/cr.pdf"
			(at 0 0 0)
			(layer "B.Fab")
			(hide yes)
			(effects
				(font
					(size 1.27 1.27)
					(thickness 0.15)
				)
				(justify mirror)
			)
		)
		(property "Description" "SMD Chip Resistor, 1 kohm, ± 1%, 63 mW, 0402 [1005 Metric], Thick Film, General Purpose"
			(at 0 0 0)
			(layer "B.Fab")
			(hide yes)
			(effects
				(font
					(size 1.27 1.27)
					(thickness 0.15)
				)
				(justify mirror)
			)
		)
		(property "MPN" "CR0402-FX-1001GLF"
			(at 0 0 0)
			(unlocked yes)
			(layer "B.Fab")
			(hide yes)
			(effects
				(font
					(size 1 1)
					(thickness 0.15)
				)
				(justify mirror)
			)
		)
		(property "Manufacturer" "Bourns"
			(at 0 0 0)
			(unlocked yes)
			(layer "B.Fab")
			(hide yes)
			(effects
				(font
					(size 1 1)
					(thickness 0.15)
				)
				(justify mirror)
			)
		)
		(property "License" "Apache-2.0"
			(at 0 0 0)
			(unlocked yes)
			(layer "B.Fab")
			(hide yes)
			(effects
				(font
					(size 1 1)
					(thickness 0.15)
				)
				(justify mirror)
			)
		)
		(property "Author" "Antmicro"
			(at 0 0 0)
			(unlocked yes)
			(layer "B.Fab")
			(hide yes)
			(effects
				(font
					(size 1 1)
					(thickness 0.15)
				)
				(justify mirror)
			)
		)
		(property "Val" "1k"
			(at 0 0 0)
			(unlocked yes)
			(layer "B.Fab")
			(hide yes)
			(effects
				(font
					(size 1 1)
					(thickness 0.15)
				)
				(justify mirror)
			)
		)
		(property "Tolerance" "1%"
			(at 0 0 0)
			(unlocked yes)
			(layer "B.Fab")
			(hide yes)
			(effects
				(font
					(size 1 1)
					(thickness 0.15)
				)
				(justify mirror)
			)
		)
		(property "Public" "False"
			(at 0 0 0)
			(unlocked yes)
			(layer "B.Fab")
			(hide yes)
			(effects
				(font
					(size 1 1)
					(thickness 0.15)
				)
				(justify mirror)
			)
		)
		(sheetname "Root")
		(sheetfile "jetson-orin-baseboard-oculink-expansion.kicad_sch")
		(attr smd dnp)
		(fp_rect
			(start -0.925 0.47)
			(end 0.925 -0.47)
			(stroke
				(width 0.05)
				(type default)
			)
			(fill none)
			(layer "B.CrtYd")
		)
		(fp_rect
			(start -0.5 0.25)
			(end 0.5 -0.25)
			(stroke
				(width 0.15)
				(type solid)
			)
			(fill none)
			(layer "B.Fab")
		)
		(fp_text user "${REFERENCE}"
			(at -0.95 -3.168 0)
			(layer "B.Fab")
			(hide yes)
			(effects
				(font
					(size 0.7 0.7)
					(thickness 0.15)
				)
				(justify left bottom mirror)
			)
		)
		(fp_text user "Author: Antmicro"
			(at -0.95 -4.169 0)
			(layer "B.Fab")
			(hide yes)
			(effects
				(font
					(size 0.7 0.7)
					(thickness 0.15)
				)
				(justify left bottom mirror)
			)
		)
		(fp_text user "License: Apache-2.0"
			(at -0.95 -5.169 0)
			(layer "B.Fab")
			(hide yes)
			(effects
				(font
					(size 0.7 0.7)
					(thickness 0.15)
				)
				(justify left bottom mirror)
			)
		)
		(pad "1" smd roundrect
			(at -0.48 0 180)
			(size 0.59 0.64)
			(layers "B.Cu" "B.Paste" "B.Mask")
			(roundrect_rratio 0.25)
			(net 23 "+3V3")
			(pintype "passive")
		)
		(pad "2" smd roundrect
			(at 0.48 0 180)
			(size 0.59 0.64)
			(layers "B.Cu" "B.Paste" "B.Mask")
			(roundrect_rratio 0.25)
			(net 89 "/RX_EQ0")
			(pintype "passive")
		)
	)
	(footprint "antmicro-footprints:C_0402_1005Metric"
		(layer "B.Cu")
		(at 126.505 114.569251 90)
		(descr "Capacitor SMD 0402")
		(tags "capacitor SMD 0402")
		(property "Reference" "C9"
			(at 1.779251 -0.415 90)
			(layer "B.SilkS")
			(effects
				(font
					(size 0.7 0.7)
					(thickness 0.15)
				)
				(justify right top mirror)
			)
		)
		(property "Value" "C_100n_0402"
			(at -1.022927 -2.155213 90)
			(layer "B.Fab")
			(effects
				(font
					(size 0.7 0.7)
					(thickness 0.15)
				)
				(justify right top mirror)
			)
		)
		(property "Footprint" "antmicro-footprints:C_0402_1005Metric"
			(at 0 0 90)
			(layer "B.Fab")
			(hide yes)
			(effects
				(font
					(size 1.27 1.27)
					(thickness 0.15)
				)
				(justify mirror)
			)
		)
		(property "Datasheet" "https://www.murata.com/products/productdetail?partno=GRM155R61H104KE14%23"
			(at 0 0 90)
			(layer "B.Fab")
			(hide yes)
			(effects
				(font
					(size 1.27 1.27)
					(thickness 0.15)
				)
				(justify mirror)
			)
		)
		(property "Description" "SMD Multilayer Ceramic Capacitor, 0.1 µF, 50 V, 0402 [1005 Metric], ± 10%, X5R, GRM Series"
			(at 0 0 90)
			(layer "B.Fab")
			(hide yes)
			(effects
				(font
					(size 1.27 1.27)
					(thickness 0.15)
				)
				(justify mirror)
			)
		)
		(property "MPN" "GRM155R61H104KE14D"
			(at 0 0 -90)
			(unlocked yes)
			(layer "B.Fab")
			(hide yes)
			(effects
				(font
					(size 1 1)
					(thickness 0.15)
				)
				(justify mirror)
			)
		)
		(property "Manufacturer" "Murata"
			(at 0 0 -90)
			(unlocked yes)
			(layer "B.Fab")
			(hide yes)
			(effects
				(font
					(size 1 1)
					(thickness 0.15)
				)
				(justify mirror)
			)
		)
		(property "License" "Apache-2.0"
			(at 0 0 -90)
			(unlocked yes)
			(layer "B.Fab")
			(hide yes)
			(effects
				(font
					(size 1 1)
					(thickness 0.15)
				)
				(justify mirror)
			)
		)
		(property "Author" "Antmicro"
			(at 0 0 -90)
			(unlocked yes)
			(layer "B.Fab")
			(hide yes)
			(effects
				(font
					(size 1 1)
					(thickness 0.15)
				)
				(justify mirror)
			)
		)
		(property "Val" "100n"
			(at 0 0 -90)
			(unlocked yes)
			(layer "B.Fab")
			(hide yes)
			(effects
				(font
					(size 1 1)
					(thickness 0.15)
				)
				(justify mirror)
			)
		)
		(property "Voltage" "50V"
			(at 0 0 -90)
			(unlocked yes)
			(layer "B.Fab")
			(hide yes)
			(effects
				(font
					(size 1 1)
					(thickness 0.15)
				)
				(justify mirror)
			)
		)
		(property "Dielectric" "X5R"
			(at 0 0 -90)
			(unlocked yes)
			(layer "B.Fab")
			(hide yes)
			(effects
				(font
					(size 1 1)
					(thickness 0.15)
				)
				(justify mirror)
			)
		)
		(property "Public" "False"
			(at 0 0 -90)
			(unlocked yes)
			(layer "B.Fab")
			(hide yes)
			(effects
				(font
					(size 1 1)
					(thickness 0.15)
				)
				(justify mirror)
			)
		)
		(sheetname "Root")
		(sheetfile "jetson-orin-baseboard-oculink-expansion.kicad_sch")
		(attr smd)
		(fp_rect
			(start -0.925 0.47)
			(end 0.925 -0.47)
			(stroke
				(width 0.05)
				(type default)
			)
			(fill none)
			(layer "B.CrtYd")
		)
		(fp_line
			(start 0.504 -0.248)
			(end 0.504 0.25)
			(stroke
				(width 0.15)
				(type solid)
			)
			(layer "B.Fab")
		)
		(fp_line
			(start -0.494 -0.248)
			(end 0.504 -0.248)
			(stroke
				(width 0.15)
				(type solid)
			)
			(layer "B.Fab")
		)
		(fp_line
			(start 0.504 0.25)
			(end -0.494 0.25)
			(stroke
				(width 0.15)
				(type solid)
			)
			(layer "B.Fab")
		)
		(fp_line
			(start -0.494 0.25)
			(end -0.494 -0.248)
			(stroke
				(width 0.15)
				(type solid)
			)
			(layer "B.Fab")
		)
		(fp_text user "License: Apache-2.0"
			(at -0.939 -5.799 90)
			(layer "B.Fab")
			(hide yes)
			(effects
				(font
					(size 0.7 0.7)
					(thickness 0.15)
				)
				(justify right top mirror)
			)
		)
		(fp_text user "${REFERENCE}"
			(at -0.939 -4.599 90)
			(layer "B.Fab")
			(hide yes)
			(effects
				(font
					(size 0.7 0.7)
					(thickness 0.15)
				)
				(justify right top mirror)
			)
		)
		(fp_text user "Author: Antmicro"
			(at -0.939 -3.399 90)
			(layer "B.Fab")
			(hide yes)
			(effects
				(font
					(size 0.7 0.7)
					(thickness 0.15)
				)
				(justify right top mirror)
			)
		)
		(pad "1" smd roundrect
			(at -0.48 0 90)
			(size 0.59 0.64)
			(layers "B.Cu" "B.Paste" "B.Mask")
			(roundrect_rratio 0.25)
			(net 51 "GND")
			(pintype "passive")
		)
		(pad "2" smd roundrect
			(at 0.48 0 90)
			(size 0.59 0.64)
			(layers "B.Cu" "B.Paste" "B.Mask")
			(roundrect_rratio 0.25)
			(net 23 "+3V3")
			(pintype "passive")
		)
	)
	(footprint "antmicro-footprints:R_0402_1005Metric"
		(layer "B.Cu")
		(at 118.324 118.193751 180)
		(descr "Resistor SMD 0402")
		(tags "resistor SMD 0402")
		(property "Reference" "R14"
			(at -3.256 -0.47725 0)
			(layer "B.SilkS")
			(effects
				(font
					(size 0.7 0.7)
					(thickness 0.15)
				)
				(justify left bottom mirror)
			)
		)
		(property "Value" "R_1k_0402"
			(at -1.011843 -1.772047 0)
			(layer "B.Fab")
			(effects
				(font
					(size 0.7 0.7)
					(thickness 0.15)
				)
				(justify left bottom mirror)
			)
		)
		(property "Footprint" "antmicro-footprints:R_0402_1005Metric"
			(at 0 0 0)
			(layer "B.Fab")
			(hide yes)
			(effects
				(font
					(size 1.27 1.27)
					(thickness 0.15)
				)
				(justify mirror)
			)
		)
		(property "Datasheet" "https://www.bourns.com/docs/product-datasheets/cr.pdf"
			(at 0 0 0)
			(layer "B.Fab")
			(hide yes)
			(effects
				(font
					(size 1.27 1.27)
					(thickness 0.15)
				)
				(justify mirror)
			)
		)
		(property "Description" "SMD Chip Resistor, 1 kohm, ± 1%, 63 mW, 0402 [1005 Metric], Thick Film, General Purpose"
			(at 0 0 0)
			(layer "B.Fab")
			(hide yes)
			(effects
				(font
					(size 1.27 1.27)
					(thickness 0.15)
				)
				(justify mirror)
			)
		)
		(property "MPN" "CR0402-FX-1001GLF"
			(at 0 0 0)
			(unlocked yes)
			(layer "B.Fab")
			(hide yes)
			(effects
				(font
					(size 1 1)
					(thickness 0.15)
				)
				(justify mirror)
			)
		)
		(property "Manufacturer" "Bourns"
			(at 0 0 0)
			(unlocked yes)
			(layer "B.Fab")
			(hide yes)
			(effects
				(font
					(size 1 1)
					(thickness 0.15)
				)
				(justify mirror)
			)
		)
		(property "License" "Apache-2.0"
			(at 0 0 0)
			(unlocked yes)
			(layer "B.Fab")
			(hide yes)
			(effects
				(font
					(size 1 1)
					(thickness 0.15)
				)
				(justify mirror)
			)
		)
		(property "Author" "Antmicro"
			(at 0 0 0)
			(unlocked yes)
			(layer "B.Fab")
			(hide yes)
			(effects
				(font
					(size 1 1)
					(thickness 0.15)
				)
				(justify mirror)
			)
		)
		(property "Val" "1k"
			(at 0 0 0)
			(unlocked yes)
			(layer "B.Fab")
			(hide yes)
			(effects
				(font
					(size 1 1)
					(thickness 0.15)
				)
				(justify mirror)
			)
		)
		(property "Tolerance" "1%"
			(at 0 0 0)
			(unlocked yes)
			(layer "B.Fab")
			(hide yes)
			(effects
				(font
					(size 1 1)
					(thickness 0.15)
				)
				(justify mirror)
			)
		)
		(property "Public" "False"
			(at 0 0 0)
			(unlocked yes)
			(layer "B.Fab")
			(hide yes)
			(effects
				(font
					(size 1 1)
					(thickness 0.15)
				)
				(justify mirror)
			)
		)
		(sheetname "Root")
		(sheetfile "jetson-orin-baseboard-oculink-expansion.kicad_sch")
		(attr smd)
		(fp_rect
			(start -0.925 0.47)
			(end 0.925 -0.47)
			(stroke
				(width 0.05)
				(type default)
			)
			(fill none)
			(layer "B.CrtYd")
		)
		(fp_rect
			(start -0.5 0.25)
			(end 0.5 -0.25)
			(stroke
				(width 0.15)
				(type solid)
			)
			(fill none)
			(layer "B.Fab")
		)
		(fp_text user "License: Apache-2.0"
			(at -0.95 -5.169 0)
			(layer "B.Fab")
			(hide yes)
			(effects
				(font
					(size 0.7 0.7)
					(thickness 0.15)
				)
				(justify left bottom mirror)
			)
		)
		(fp_text user "${REFERENCE}"
			(at -0.95 -3.168 0)
			(layer "B.Fab")
			(hide yes)
			(effects
				(font
					(size 0.7 0.7)
					(thickness 0.15)
				)
				(justify left bottom mirror)
			)
		)
		(fp_text user "Author: Antmicro"
			(at -0.95 -4.169 0)
			(layer "B.Fab")
			(hide yes)
			(effects
				(font
					(size 0.7 0.7)
					(thickness 0.15)
				)
				(justify left bottom mirror)
			)
		)
		(pad "1" smd roundrect
			(at -0.48 0 180)
			(size 0.59 0.64)
			(layers "B.Cu" "B.Paste" "B.Mask")
			(roundrect_rratio 0.25)
			(net 23 "+3V3")
			(pintype "passive")
		)
		(pad "2" smd roundrect
			(at 0.48 0 180)
			(size 0.59 0.64)
			(layers "B.Cu" "B.Paste" "B.Mask")
			(roundrect_rratio 0.25)
			(net 94 "/RX_SW")
			(pintype "passive")
		)
	)
	(footprint "antmicro-footprints:R_0402_1005Metric"
		(layer "B.Cu")
		(at 129.794 128.00775 180)
		(descr "Resistor SMD 0402")
		(tags "resistor SMD 0402")
		(property "Reference" "R19"
			(at -3.336 -0.42225 0)
			(layer "B.SilkS")
			(effects
				(font
					(size 0.7 0.7)
					(thickness 0.15)
				)
				(justify left bottom mirror)
			)
		)
		(property "Value" "R_1k_0402"
			(at -1.011843 -1.772047 0)
			(layer "B.Fab")
			(effects
				(font
					(size 0.7 0.7)
					(thickness 0.15)
				)
				(justify left bottom mirror)
			)
		)
		(property "Footprint" "antmicro-footprints:R_0402_1005Metric"
			(at 0 0 0)
			(layer "B.Fab")
			(hide yes)
			(effects
				(font
					(size 1.27 1.27)
					(thickness 0.15)
				)
				(justify mirror)
			)
		)
		(property "Datasheet" "https://www.bourns.com/docs/product-datasheets/cr.pdf"
			(at 0 0 0)
			(layer "B.Fab")
			(hide yes)
			(effects
				(font
					(size 1.27 1.27)
					(thickness 0.15)
				)
				(justify mirror)
			)
		)
		(property "Description" "SMD Chip Resistor, 1 kohm, ± 1%, 63 mW, 0402 [1005 Metric], Thick Film, General Purpose"
			(at 0 0 0)
			(layer "B.Fab")
			(hide yes)
			(effects
				(font
					(size 1.27 1.27)
					(thickness 0.15)
				)
				(justify mirror)
			)
		)
		(property "MPN" "CR0402-FX-1001GLF"
			(at 0 0 0)
			(unlocked yes)
			(layer "B.Fab")
			(hide yes)
			(effects
				(font
					(size 1 1)
					(thickness 0.15)
				)
				(justify mirror)
			)
		)
		(property "Manufacturer" "Bourns"
			(at 0 0 0)
			(unlocked yes)
			(layer "B.Fab")
			(hide yes)
			(effects
				(font
					(size 1 1)
					(thickness 0.15)
				)
				(justify mirror)
			)
		)
		(property "License" "Apache-2.0"
			(at 0 0 0)
			(unlocked yes)
			(layer "B.Fab")
			(hide yes)
			(effects
				(font
					(size 1 1)
					(thickness 0.15)
				)
				(justify mirror)
			)
		)
		(property "Author" "Antmicro"
			(at 0 0 0)
			(unlocked yes)
			(layer "B.Fab")
			(hide yes)
			(effects
				(font
					(size 1 1)
					(thickness 0.15)
				)
				(justify mirror)
			)
		)
		(property "Val" "1k"
			(at 0 0 0)
			(unlocked yes)
			(layer "B.Fab")
			(hide yes)
			(effects
				(font
					(size 1 1)
					(thickness 0.15)
				)
				(justify mirror)
			)
		)
		(property "Tolerance" "1%"
			(at 0 0 0)
			(unlocked yes)
			(layer "B.Fab")
			(hide yes)
			(effects
				(font
					(size 1 1)
					(thickness 0.15)
				)
				(justify mirror)
			)
		)
		(property "Public" "False"
			(at 0 0 0)
			(unlocked yes)
			(layer "B.Fab")
			(hide yes)
			(effects
				(font
					(size 1 1)
					(thickness 0.15)
				)
				(justify mirror)
			)
		)
		(sheetname "Root")
		(sheetfile "jetson-orin-baseboard-oculink-expansion.kicad_sch")
		(attr smd)
		(fp_rect
			(start -0.925 0.47)
			(end 0.925 -0.47)
			(stroke
				(width 0.05)
				(type default)
			)
			(fill none)
			(layer "B.CrtYd")
		)
		(fp_rect
			(start -0.5 0.25)
			(end 0.5 -0.25)
			(stroke
				(width 0.15)
				(type solid)
			)
			(fill none)
			(layer "B.Fab")
		)
		(fp_text user "Author: Antmicro"
			(at -0.95 -4.169 0)
			(layer "B.Fab")
			(hide yes)
			(effects
				(font
					(size 0.7 0.7)
					(thickness 0.15)
				)
				(justify left bottom mirror)
			)
		)
		(fp_text user "License: Apache-2.0"
			(at -0.95 -5.169 0)
			(layer "B.Fab")
			(hide yes)
			(effects
				(font
					(size 0.7 0.7)
					(thickness 0.15)
				)
				(justify left bottom mirror)
			)
		)
		(fp_text user "${REFERENCE}"
			(at -0.95 -3.168 0)
			(layer "B.Fab")
			(hide yes)
			(effects
				(font
					(size 0.7 0.7)
					(thickness 0.15)
				)
				(justify left bottom mirror)
			)
		)
		(pad "1" smd roundrect
			(at -0.48 0 180)
			(size 0.59 0.64)
			(layers "B.Cu" "B.Paste" "B.Mask")
			(roundrect_rratio 0.25)
			(net 51 "GND")
			(pintype "passive")
		)
		(pad "2" smd roundrect
			(at 0.48 0 180)
			(size 0.59 0.64)
			(layers "B.Cu" "B.Paste" "B.Mask")
			(roundrect_rratio 0.25)
			(net 96 "/TX_EQ0")
			(pintype "passive")
		)
	)
)
